# S9S_MB_2U (Grand Teton) — schematic netlist excerpt (pin names and nets, part order shuffled) for the footprints in the layout excerpt that follows; sources: Cadence DE-HDL packaged netlist, KiCad conversion of 03242023_DA0F0TMBIJ0_F0T_Motherboard_J_brd_V01_OCP.brd

J90  SCONN56_123276793  SCONN56_1-2327679-3 IO  pkg CON_F56S2H4D_P0-6W4-6_LUHXA  page 191
  GND_A1  = GND
  GND_A2  = GND
  GND_A3  = GND
  GND_A4  = GND
  GND_A5  = GND
  GND_A6  = GND
  SMBCLK  = SMB_E1S_3V3AUX_ISO_SCL
  SMBDAT  = SMB_E1S_3V3AUX_ISO_SDA
  \smbrst#\  = RST_SMB_E1S_0_N
  \led#_activity\  = E1S_0_LED_ACT_N
  \perst1#_clkreq#\  = E1S_0_PERST1_CLKREQ_N
  \prsnt0#\  = E1S_0_PRSNT_N
  GND_A13  = GND
  REFCLK_N1  = TP_CLK_100M_E1S_0_DN
  REFCLK_P1  = TP_CLK_100M_E1S_0_DP
  GND_A16  = GND
  PER_N0  = P3E_PCH_E1S_RX_DP<0>
  PER_P0  = P3E_PCH_E1S_RX_DN<0>
  GND_A19  = GND
  PER_N1  = P3E_PCH_E1S_RX_DN<1>
  PER_P1  = P3E_PCH_E1S_RX_DP<1>
  GND_A22  = GND
  PER_N2  = P3E_PCH_E1S_RX_DN<2>
  PER_P2  = P3E_PCH_E1S_RX_DP<2>
  GND_A25  = GND
  PER_N3  = P3E_PCH_E1S_RX_DN<3>
  PER_P3  = P3E_PCH_E1S_RX_DP<3>
  GND_A28  = GND
  P12V_B1  = P12V_E1S_0
  P12V_B2  = P12V_E1S_0
  P12V_B3  = P12V_E1S_0
  P12V_B4  = P12V_E1S_0
  P12V_B5  = P12V_E1S_0
  P12V_B6  = P12V_E1S_0
  MFG  = TP_E1S_0_MFG
  RFU  = TP_E1S_0_RFU
  \dualporten#\  = PU_E1S_0_DUALPORT_EN_N
  \perst0#\  = RST_PCIE_PCH_E1S_PERST_N
  P3V3_AUX  = P3V3_E1S_0
  PWRDIS  = E1S_0_PWRDIS
  GND_B13  = GND
  REFCLK_N0  = CLK_100M_E1S_0_DN
  REFCLK_P0  = CLK_100M_E1S_0_DP
  GND_B16  = GND
  PET_N0  = P3E_PCH_E1S_TX_C_DP<0>
  PET_P0  = P3E_PCH_E1S_TX_C_DN<0>
  GND_B19  = GND
  PET_N1  = P3E_PCH_E1S_TX_C_DP<1>
  PET_P1  = P3E_PCH_E1S_TX_C_DN<1>
  GND_B22  = GND
  PET_N2  = P3E_PCH_E1S_TX_C_DN<2>
  PET_P2  = P3E_PCH_E1S_TX_C_DP<2>
  GND_B25  = GND
  PET_N3  = P3E_PCH_E1S_TX_C_DN<3>
  PET_P3  = P3E_PCH_E1S_TX_C_DP<3>
  GND_B28  = GND
  G1  = GND
  G2  = GND

(kicad_pcb
	(version 20260206)
	(generator "pcbnew")
	(generator_version "10.0")
	(general
		(thickness 1.6)
		(legacy_teardrops no)
	)
	(paper "A4")
	(title_block
		(title "03242023_DA0F0TMBIJ0_F0T_Motherboard_J_brd_V01_OCP.brd")
		(comment 1 "Grand Teton / footprint 2802 of 6105 (J90), pads 47-60 of 60")
	)
	(layers
		(0 "F.Cu" signal "TOP")
		(4 "In1.Cu" signal "GND")
		(6 "In2.Cu" signal "IN1")
		(8 "In3.Cu" signal "GND1")
		(10 "In4.Cu" signal "IN2")
		(12 "In5.Cu" signal "GND2")
		(14 "In6.Cu" signal "IN3")
		(16 "In7.Cu" signal "GND3")
		(18 "In8.Cu" signal "VCC")
		(20 "In9.Cu" signal "VCC1")
		(22 "In10.Cu" signal "GND4")
		(24 "In11.Cu" signal "IN4")
		(26 "In12.Cu" signal "GND5")
		(28 "In13.Cu" signal "IN5")
		(30 "In14.Cu" signal "GND6")
		(32 "In15.Cu" signal "IN6")
		(34 "In16.Cu" signal "GND7")
		(2 "B.Cu" signal "BOTTOM")
		(9 "F.Adhes" user "F.Adhesive")
		(11 "B.Adhes" user "B.Adhesive")
		(13 "F.Paste" user "Package Geometry/Pastemask Top")
		(15 "B.Paste" user "Package Geometry/Pastemask Bottom")
		(5 "F.SilkS" user "Ref Des/Silkscreen Top")
		(7 "B.SilkS" user "Ref Des/Silkscreen Bottom")
		(1 "F.Mask" user "Board Geometry/Soldermask Top")
		(3 "B.Mask" user "Board Geometry/Soldermask Bottom")
		(17 "Dwgs.User" user "User.Drawings")
		(19 "Cmts.User" user "User.Comments")
		(21 "Eco1.User" user "User.Eco1")
		(23 "Eco2.User" user "User.Eco2")
		(25 "Edge.Cuts" user "Board Geometry/Outline")
		(27 "Margin" user)
		(31 "F.CrtYd" user "Package Geometry/Place Bound Top")
		(29 "B.CrtYd" user "Package Geometry/Place Bound Bottom")
		(35 "F.Fab" user "Ref Des/Assembly Top")
		(33 "B.Fab" user "Ref Des/Assembly Bottom")
	)
	(footprint ""
		(layer "F.Cu")
		(at 234.300014 -50.55997 180)
		(property "Reference" "J90"
			(at -0.596646 16.126968 0)
			(unlocked yes)
			(layer "F.SilkS")
			(effects
				(font
					(size 0.7874 0.5842)
					(thickness 0.1524)
				)
			)
		)
		(property "Value" ""
			(at 0 0 180)
			(layer "F.Fab")
			(effects
				(font
					(size 1.27 1.27)
				)
			)
		)
		(duplicate_pad_numbers_are_jumpers no)
		(pad "B17" smd rect
			(at -2.29997 1.605026 90)
			(size 0.381 1.27)
			(layers "F.Cu" "F.Mask" "F.Paste")
			(net "P3E_PCH_E1S_TX_C_DP<0>")
		)
		(pad "B18" smd rect
			(at -2.29997 2.204974 90)
			(size 0.381 1.27)
			(layers "F.Cu" "F.Mask" "F.Paste")
			(net "P3E_PCH_E1S_TX_C_DN<0>")
		)
		(pad "B19" smd rect
			(at -2.29997 2.804922 90)
			(size 0.381 1.27)
			(layers "F.Cu" "F.Mask" "F.Paste")
			(net "GND")
		)
		(pad "B20" smd rect
			(at -2.29997 3.405124 90)
			(size 0.381 1.27)
			(layers "F.Cu" "F.Mask" "F.Paste")
			(net "P3E_PCH_E1S_TX_C_DP<1>")
		)
		(pad "B21" smd rect
			(at -2.29997 4.005072 90)
			(size 0.381 1.27)
			(layers "F.Cu" "F.Mask" "F.Paste")
			(net "P3E_PCH_E1S_TX_C_DN<1>")
		)
		(pad "B22" smd rect
			(at -2.29997 4.60502 90)
			(size 0.381 1.27)
			(layers "F.Cu" "F.Mask" "F.Paste")
			(net "GND")
		)
		(pad "B23" smd rect
			(at -2.29997 5.204968 90)
			(size 0.381 1.27)
			(layers "F.Cu" "F.Mask" "F.Paste")
			(net "P3E_PCH_E1S_TX_C_DN<2>")
		)
		(pad "B24" smd rect
			(at -2.29997 5.804916 90)
			(size 0.381 1.27)
			(layers "F.Cu" "F.Mask" "F.Paste")
			(net "P3E_PCH_E1S_TX_C_DP<2>")
		)
		(pad "B25" smd rect
			(at -2.29997 6.405118 90)
			(size 0.381 1.27)
			(layers "F.Cu" "F.Mask" "F.Paste")
			(net "GND")
		)
		(pad "B26" smd rect
			(at -2.29997 7.005066 90)
			(size 0.381 1.27)
			(layers "F.Cu" "F.Mask" "F.Paste")
			(net "P3E_PCH_E1S_TX_C_DN<3>")
		)
		(pad "B27" smd rect
			(at -2.29997 7.605014 90)
			(size 0.381 1.27)
			(layers "F.Cu" "F.Mask" "F.Paste")
			(net "P3E_PCH_E1S_TX_C_DP<3>")
		)
		(pad "B28" smd rect
			(at -2.29997 8.204962 90)
			(size 0.381 1.27)
			(layers "F.Cu" "F.Mask" "F.Paste")
			(net "GND")
		)
		(pad "G1" thru_hole oval
			(at 0 -11.364976 90)
			(size 1.6256 3.4798)
			(drill oval 1.1176 2.4638)
			(layers "*.Cu" "*.Mask")
			(remove_unused_layers no)
			(net "GND")
			(clearance 0.127)
			(thermal_gap 0.127)
		)
		(pad "G2" thru_hole oval
			(at 0 11.364976 90)
			(size 1.6256 3.4798)
			(drill oval 1.1176 2.4638)
			(layers "*.Cu" "*.Mask")
			(remove_unused_layers no)
			(net "GND")
			(clearance 0.127)
			(thermal_gap 0.127)
		)
	)
)
